# T6G (Grand Teton) — schematic netlist excerpt (pin names and nets, part order shuffled) for the footprints in the layout excerpt that follows; sources: Cadence DE-HDL packaged netlist, KiCad conversion of 04192023_DAF0TMB3IC0_F0TG_MB_C_brd_V02_OCP.brd

PU21  RAA229621GNPHA0  RAA229621GNP#HA0 IC  pkg QFN40_TH_0-4_5X5XE  page 207
  PWM0  = NC_PVDD11_S3_P0_PWM8
  PWM1  = NC_PVDD11_S3_P0_PWM7
  PWM2  = NC_PVDD11_S3_P0_PWM6
  PWM3  = NC_PVDD11_S3_P0_PWM5
  PWM4  = NC_PVDD11_S3_P0_PWM4
  PWM5  = NC_PVDD11_S3_P0_PWM3
  PWM6  = PVDD11_S3_P0_PWM2
  PWM7  = PVDD11_S3_P0_PWM1
  PMSDA  = PVDD11_S3_P0_PMSDA_R
  PMSCL  = PVDD11_S3_P0_PMSCL_R
  NPMALERT  = PVDD11_S3_P0_PMALERT_R
  PG0  = PWRGD_PVDD11_S3_P0_R
  EN0  = PVDD11_S3_P0_EN_R
  RESET_L  = PVDD11_S3_P0_RESET_N_R
  VDDIO  = PVDD11_S3_P0_VDDIO
  PG1  = NC_PVDD11_S3_P0_PG1
  SVD  = GND
  SVC  = GND
  SVTO  = NC_PVDD11_S3_P0_SVTO
  SVTI  = GND
  VSEN0  = VSENSE_PVDD11_S3_P0_R
  RGND0  = VSENSE_VSS_SENSE_C_P0
  CS7  = PVDD11_S3_P0_IMON1
  CS6  = PVDD11_S3_P0_IMON2
  CS5  = NC_PVDD11_S3_P0_IMON3
  CS4  = NC_PVDD11_S3_P0_IMON4
  CS3  = NC_PVDD11_S3_P0_IMON5
  CS2  = NC_PVDD11_S3_P0_IMON6
  CS1  = NC_PVDD11_S3_P0_IMON7
  CS0  = NC_PVDD11_S3_P0_IMON8
  RGND1  = GND
  VSEN1  = GND
  OCP_L  = PVDD11_S3_P0_OCP_N_R
  \en1||addr_cfg\  = PVDD11_S3_P0_ADDR_CFG
  TEMP1  = PVDD11_S3_P0_TEMP1
  TEMP0  = PVDD11_S3_P0_TEMP0
  \vmon||iinsen\  = PVDD11_S3_P0_VMON
  VINSEN  = PVDD11_S3_P0_VINSEN
  VCC  = PVDD11_S3_P0_VCC
  VCCS  = PVDD11_S3_P0_VCCS
  TH_GND  = GND

(kicad_pcb
	(version 20260206)
	(generator "pcbnew")
	(generator_version "10.0")
	(general
		(thickness 1.6)
		(legacy_teardrops no)
	)
	(paper "A4")
	(title_block
		(title "04192023_DAF0TMB3IC0_F0TG_MB_C_brd_V02_OCP.brd")
		(comment 1 "Grand Teton / footprint 4277 of 8354 (PU21), pads 1-41 of 41")
	)
	(layers
		(0 "F.Cu" signal "TOP")
		(4 "In1.Cu" signal "GND")
		(6 "In2.Cu" signal "IN1")
		(8 "In3.Cu" signal "GND1")
		(10 "In4.Cu" signal "IN2")
		(12 "In5.Cu" signal "GND2")
		(14 "In6.Cu" signal "IN3")
		(16 "In7.Cu" signal "GND3")
		(18 "In8.Cu" signal "VCC")
		(20 "In9.Cu" signal "VCC1")
		(22 "In10.Cu" signal "GND4")
		(24 "In11.Cu" signal "IN4")
		(26 "In12.Cu" signal "GND5")
		(28 "In13.Cu" signal "IN5")
		(30 "In14.Cu" signal "GND6")
		(32 "In15.Cu" signal "IN6")
		(34 "In16.Cu" signal "GND7")
		(2 "B.Cu" signal "BOTTOM")
		(9 "F.Adhes" user "F.Adhesive")
		(11 "B.Adhes" user "B.Adhesive")
		(13 "F.Paste" user "Package Geometry/Pastemask Top")
		(15 "B.Paste" user "Package Geometry/Pastemask Bottom")
		(5 "F.SilkS" user "Ref Des/Silkscreen Top")
		(7 "B.SilkS" user "Ref Des/Silkscreen Bottom")
		(1 "F.Mask" user "Board Geometry/Soldermask Top")
		(3 "B.Mask" user "Board Geometry/Soldermask Bottom")
		(17 "Dwgs.User" user "User.Drawings")
		(19 "Cmts.User" user "User.Comments")
		(21 "Eco1.User" user "User.Eco1")
		(23 "Eco2.User" user "User.Eco2")
		(25 "Edge.Cuts" user "Board Geometry/Outline")
		(27 "Margin" user)
		(31 "F.CrtYd" user "Package Geometry/Place Bound Top")
		(29 "B.CrtYd" user "Package Geometry/Place Bound Bottom")
		(35 "F.Fab" user "Ref Des/Assembly Top")
		(33 "B.Fab" user "Ref Des/Assembly Bottom")
	)
	(footprint ""
		(layer "F.Cu")
		(at 418.917882 -362.087414 -90)
		(property "Reference" "PU21"
			(at -5.639816 -0.501904 0)
			(unlocked yes)
			(layer "F.SilkS")
			(effects
				(font
					(size 0.7874 0.5842)
					(thickness 0.1524)
				)
				(justify left)
			)
		)
		(property "Value" ""
			(at 0 0 270)
			(layer "F.Fab")
			(effects
				(font
					(size 1.27 1.27)
				)
			)
		)
		(duplicate_pad_numbers_are_jumpers no)
		(pad "1" smd rect
			(at -2.400046 -1.800098 180)
			(size 0.1778 0.6096)
			(layers "F.Cu" "F.Mask" "F.Paste")
			(net "NC_PVDD11_S3_P0_PWM8")
		)
		(pad "2" smd rect
			(at -2.400046 -1.400048 180)
			(size 0.1778 0.6096)
			(layers "F.Cu" "F.Mask" "F.Paste")
			(net "NC_PVDD11_S3_P0_PWM7")
		)
		(pad "3" smd rect
			(at -2.400046 -0.999998 180)
			(size 0.1778 0.6096)
			(layers "F.Cu" "F.Mask" "F.Paste")
			(net "NC_PVDD11_S3_P0_PWM6")
		)
		(pad "4" smd rect
			(at -2.400046 -0.599948 180)
			(size 0.1778 0.6096)
			(layers "F.Cu" "F.Mask" "F.Paste")
			(net "NC_PVDD11_S3_P0_PWM5")
		)
		(pad "5" smd rect
			(at -2.400046 -0.199898 180)
			(size 0.1778 0.6096)
			(layers "F.Cu" "F.Mask" "F.Paste")
			(net "NC_PVDD11_S3_P0_PWM4")
		)
		(pad "6" smd rect
			(at -2.400046 0.199898 180)
			(size 0.1778 0.6096)
			(layers "F.Cu" "F.Mask" "F.Paste")
			(net "NC_PVDD11_S3_P0_PWM3")
		)
		(pad "7" smd rect
			(at -2.400046 0.599948 180)
			(size 0.1778 0.6096)
			(layers "F.Cu" "F.Mask" "F.Paste")
			(net "PVDD11_S3_P0_PWM2")
		)
		(pad "8" smd rect
			(at -2.400046 0.999998 180)
			(size 0.1778 0.6096)
			(layers "F.Cu" "F.Mask" "F.Paste")
			(net "PVDD11_S3_P0_PWM1")
		)
		(pad "9" smd rect
			(at -2.400046 1.400048 180)
			(size 0.1778 0.6096)
			(layers "F.Cu" "F.Mask" "F.Paste")
			(net "PVDD11_S3_P0_PMSDA_R")
		)
		(pad "10" smd rect
			(at -2.400046 1.800098 180)
			(size 0.1778 0.6096)
			(layers "F.Cu" "F.Mask" "F.Paste")
			(net "PVDD11_S3_P0_PMSCL_R")
		)
		(pad "11" smd rect
			(at -1.800098 2.400046 270)
			(size 0.1778 0.6096)
			(layers "F.Cu" "F.Mask" "F.Paste")
			(net "PVDD11_S3_P0_PMALERT_R")
		)
		(pad "12" smd rect
			(at -1.400048 2.400046 270)
			(size 0.1778 0.6096)
			(layers "F.Cu" "F.Mask" "F.Paste")
			(net "PWRGD_PVDD11_S3_P0_R")
		)
		(pad "13" smd rect
			(at -0.999998 2.400046 270)
			(size 0.1778 0.6096)
			(layers "F.Cu" "F.Mask" "F.Paste")
			(net "PVDD11_S3_P0_EN_R")
		)
		(pad "14" smd rect
			(at -0.599948 2.400046 270)
			(size 0.1778 0.6096)
			(layers "F.Cu" "F.Mask" "F.Paste")
			(net "PVDD11_S3_P0_RESET_N_R")
		)
		(pad "15" smd rect
			(at -0.199898 2.400046 270)
			(size 0.1778 0.6096)
			(layers "F.Cu" "F.Mask" "F.Paste")
			(net "PVDD11_S3_P0_VDDIO")
		)
		(pad "16" smd rect
			(at 0.199898 2.400046 270)
			(size 0.1778 0.6096)
			(layers "F.Cu" "F.Mask" "F.Paste")
			(net "NC_PVDD11_S3_P0_PG1")
		)
		(pad "17" smd rect
			(at 0.599948 2.400046 270)
			(size 0.1778 0.6096)
			(layers "F.Cu" "F.Mask" "F.Paste")
			(net "GND")
		)
		(pad "18" smd rect
			(at 0.999998 2.400046 270)
			(size 0.1778 0.6096)
			(layers "F.Cu" "F.Mask" "F.Paste")
			(net "GND")
		)
		(pad "19" smd rect
			(at 1.400048 2.400046 270)
			(size 0.1778 0.6096)
			(layers "F.Cu" "F.Mask" "F.Paste")
			(net "NC_PVDD11_S3_P0_SVTO")
		)
		(pad "20" smd rect
			(at 1.800098 2.400046 270)
			(size 0.1778 0.6096)
			(layers "F.Cu" "F.Mask" "F.Paste")
			(net "GND")
		)
		(pad "21" smd rect
			(at 2.400046 1.800098 180)
			(size 0.1778 0.6096)
			(layers "F.Cu" "F.Mask" "F.Paste")
			(net "VSENSE_PVDD11_S3_P0_R")
		)
		(pad "22" smd rect
			(at 2.400046 1.400048 180)
			(size 0.1778 0.6096)
			(layers "F.Cu" "F.Mask" "F.Paste")
			(net "VSENSE_VSS_SENSE_C_P0")
		)
		(pad "23" smd rect
			(at 2.400046 0.999998 180)
			(size 0.1778 0.6096)
			(layers "F.Cu" "F.Mask" "F.Paste")
			(net "PVDD11_S3_P0_IMON1")
		)
		(pad "24" smd rect
			(at 2.400046 0.599948 180)
			(size 0.1778 0.6096)
			(layers "F.Cu" "F.Mask" "F.Paste")
			(net "PVDD11_S3_P0_IMON2")
		)
		(pad "25" smd rect
			(at 2.400046 0.199898 180)
			(size 0.1778 0.6096)
			(layers "F.Cu" "F.Mask" "F.Paste")
			(net "NC_PVDD11_S3_P0_IMON3")
		)
		(pad "26" smd rect
			(at 2.400046 -0.199898 180)
			(size 0.1778 0.6096)
			(layers "F.Cu" "F.Mask" "F.Paste")
			(net "NC_PVDD11_S3_P0_IMON4")
		)
		(pad "27" smd rect
			(at 2.400046 -0.599948 180)
			(size 0.1778 0.6096)
			(layers "F.Cu" "F.Mask" "F.Paste")
			(net "NC_PVDD11_S3_P0_IMON5")
		)
		(pad "28" smd rect
			(at 2.400046 -0.999998 180)
			(size 0.1778 0.6096)
			(layers "F.Cu" "F.Mask" "F.Paste")
			(net "NC_PVDD11_S3_P0_IMON6")
		)
		(pad "29" smd rect
			(at 2.400046 -1.400048 180)
			(size 0.1778 0.6096)
			(layers "F.Cu" "F.Mask" "F.Paste")
			(net "NC_PVDD11_S3_P0_IMON7")
		)
		(pad "30" smd rect
			(at 2.400046 -1.800098 180)
			(size 0.1778 0.6096)
			(layers "F.Cu" "F.Mask" "F.Paste")
			(net "NC_PVDD11_S3_P0_IMON8")
		)
		(pad "31" smd rect
			(at 1.800098 -2.400046 270)
			(size 0.1778 0.6096)
			(layers "F.Cu" "F.Mask" "F.Paste")
			(net "GND")
		)
		(pad "32" smd rect
			(at 1.400048 -2.400046 270)
			(size 0.1778 0.6096)
			(layers "F.Cu" "F.Mask" "F.Paste")
			(net "GND")
		)
		(pad "33" smd rect
			(at 0.999998 -2.400046 270)
			(size 0.1778 0.6096)
			(layers "F.Cu" "F.Mask" "F.Paste")
			(net "PVDD11_S3_P0_OCP_N_R")
		)
		(pad "34" smd rect
			(at 0.599948 -2.400046 270)
			(size 0.1778 0.6096)
			(layers "F.Cu" "F.Mask" "F.Paste")
			(net "PVDD11_S3_P0_ADDR_CFG")
		)
		(pad "35" smd rect
			(at 0.199898 -2.400046 270)
			(size 0.1778 0.6096)
			(layers "F.Cu" "F.Mask" "F.Paste")
			(net "PVDD11_S3_P0_TEMP1")
		)
		(pad "36" smd rect
			(at -0.199898 -2.400046 270)
			(size 0.1778 0.6096)
			(layers "F.Cu" "F.Mask" "F.Paste")
			(net "PVDD11_S3_P0_TEMP0")
		)
		(pad "37" smd rect
			(at -0.599948 -2.400046 270)
			(size 0.1778 0.6096)
			(layers "F.Cu" "F.Mask" "F.Paste")
			(net "PVDD11_S3_P0_VMON")
		)
		(pad "38" smd rect
			(at -0.999998 -2.400046 270)
			(size 0.1778 0.6096)
			(layers "F.Cu" "F.Mask" "F.Paste")
			(net "PVDD11_S3_P0_VINSEN")
		)
		(pad "39" smd rect
			(at -1.400048 -2.400046 270)
			(size 0.1778 0.6096)
			(layers "F.Cu" "F.Mask" "F.Paste")
			(net "PVDD11_S3_P0_VCC")
		)
		(pad "40" smd rect
			(at -1.800098 -2.400046 270)
			(size 0.1778 0.6096)
			(layers "F.Cu" "F.Mask" "F.Paste")
			(net "PVDD11_S3_P0_VCCS")
		)
		(pad "TH" smd rect
			(at 0 0 270)
			(size 3.6576 3.6576)
			(layers "F.Cu" "F.Mask" "F.Paste")
			(net "GND")
		)
	)
)
